# T6G (Grand Teton) — schematic netlist excerpt (pin names and nets, part order shuffled) for the footprints in the layout excerpt that follows; sources: Cadence DE-HDL packaged netlist, KiCad conversion of 04192023_DAF0TMB3IC0_F0TG_MB_C_brd_V02_OCP.brd

PC7003  Q_CAP  22UF 16V 20% X6S  pkg C0805  page 225 : A = SW_P12V_AUX_PVDD11_S3_P1_FLT ; B = GND
C172  Q_CAP  0.1UF 25V 10% X7R  pkg 0402  page 107 : A = P3V3_AUX ; B = GND
C1708  Q_CAP  0.1UF 25V 10% X7R  pkg 0402  page 248 : A = P3V3_AUX ; B = GND

(kicad_pcb
	(version 20260206)
	(generator "pcbnew")
	(generator_version "10.0")
	(general
		(thickness 1.6)
		(legacy_teardrops no)
	)
	(paper "A4")
	(title_block
		(title "04192023_DAF0TMB3IC0_F0TG_MB_C_brd_V02_OCP.brd")
		(comment 1 "Grand Teton / footprints 6004-6006 of 8354")
	)
	(layers
		(0 "F.Cu" signal "TOP")
		(4 "In1.Cu" signal "GND")
		(6 "In2.Cu" signal "IN1")
		(8 "In3.Cu" signal "GND1")
		(10 "In4.Cu" signal "IN2")
		(12 "In5.Cu" signal "GND2")
		(14 "In6.Cu" signal "IN3")
		(16 "In7.Cu" signal "GND3")
		(18 "In8.Cu" signal "VCC")
		(20 "In9.Cu" signal "VCC1")
		(22 "In10.Cu" signal "GND4")
		(24 "In11.Cu" signal "IN4")
		(26 "In12.Cu" signal "GND5")
		(28 "In13.Cu" signal "IN5")
		(30 "In14.Cu" signal "GND6")
		(32 "In15.Cu" signal "IN6")
		(34 "In16.Cu" signal "GND7")
		(2 "B.Cu" signal "BOTTOM")
		(9 "F.Adhes" user "F.Adhesive")
		(11 "B.Adhes" user "B.Adhesive")
		(13 "F.Paste" user "Package Geometry/Pastemask Top")
		(15 "B.Paste" user "Package Geometry/Pastemask Bottom")
		(5 "F.SilkS" user "Ref Des/Silkscreen Top")
		(7 "B.SilkS" user "Ref Des/Silkscreen Bottom")
		(1 "F.Mask" user "Board Geometry/Soldermask Top")
		(3 "B.Mask" user "Board Geometry/Soldermask Bottom")
		(17 "Dwgs.User" user "User.Drawings")
		(19 "Cmts.User" user "User.Comments")
		(21 "Eco1.User" user "User.Eco1")
		(23 "Eco2.User" user "User.Eco2")
		(25 "Edge.Cuts" user "Board Geometry/Outline")
		(27 "Margin" user)
		(31 "F.CrtYd" user "Package Geometry/Place Bound Top")
		(29 "B.CrtYd" user "Package Geometry/Place Bound Bottom")
		(35 "F.Fab" user "Ref Des/Assembly Top")
		(33 "B.Fab" user "Ref Des/Assembly Bottom")
	)
	(footprint ""
		(layer "B.Cu")
		(at 190.404496 -193.996564)
		(property "Reference" "C172"
			(at 0 0 0)
			(layer "B.SilkS")
			(hide yes)
			(effects
				(font
					(size 1.27 1.27)
				)
				(justify mirror)
			)
		)
		(property "Value" ""
			(at 0 0 0)
			(layer "B.Fab")
			(effects
				(font
					(size 1.27 1.27)
				)
				(justify mirror)
			)
		)
		(duplicate_pad_numbers_are_jumpers no)
		(fp_line
			(start -0.7874 -0.4064)
			(end -0.7874 0.4064)
			(stroke
				(width 0.1524)
				(type default)
			)
			(layer "B.SilkS")
		)
		(fp_line
			(start -0.7874 0.4064)
			(end 0.7874 0.4064)
			(stroke
				(width 0.1524)
				(type default)
			)
			(layer "B.SilkS")
		)
		(fp_line
			(start 0.7874 -0.4064)
			(end -0.7874 -0.4064)
			(stroke
				(width 0.1524)
				(type default)
			)
			(layer "B.SilkS")
		)
		(fp_line
			(start 0.7874 0.4064)
			(end 0.7874 -0.4064)
			(stroke
				(width 0.1524)
				(type default)
			)
			(layer "B.SilkS")
		)
		(fp_line
			(start -0.67945 -0.3048)
			(end -0.67945 0.3048)
			(stroke
				(width 0.1)
				(type default)
			)
			(layer "B.Fab")
		)
		(fp_line
			(start -0.67945 0.3048)
			(end -0.120396 0.3048)
			(stroke
				(width 0.1)
				(type default)
			)
			(layer "B.Fab")
		)
		(fp_line
			(start -0.12065 -0.3048)
			(end -0.67945 -0.3048)
			(stroke
				(width 0.1)
				(type default)
			)
			(layer "B.Fab")
		)
		(fp_line
			(start -0.12065 -0.2794)
			(end -0.12065 -0.3048)
			(stroke
				(width 0.1)
				(type default)
			)
			(layer "B.Fab")
		)
		(fp_line
			(start -0.120396 0.2794)
			(end 0.12065 0.2794)
			(stroke
				(width 0.1)
				(type default)
			)
			(layer "B.Fab")
		)
		(fp_line
			(start -0.120396 0.3048)
			(end -0.120396 0.2794)
			(stroke
				(width 0.1)
				(type default)
			)
			(layer "B.Fab")
		)
		(fp_line
			(start 0.12065 -0.305054)
			(end 0.12065 -0.2794)
			(stroke
				(width 0.1)
				(type default)
			)
			(layer "B.Fab")
		)
		(fp_line
			(start 0.12065 -0.2794)
			(end -0.12065 -0.2794)
			(stroke
				(width 0.1)
				(type default)
			)
			(layer "B.Fab")
		)
		(fp_line
			(start 0.12065 0.2794)
			(end 0.12065 0.3048)
			(stroke
				(width 0.1)
				(type default)
			)
			(layer "B.Fab")
		)
		(fp_line
			(start 0.12065 0.3048)
			(end 0.67945 0.3048)
			(stroke
				(width 0.1)
				(type default)
			)
			(layer "B.Fab")
		)
		(fp_line
			(start 0.67945 -0.305054)
			(end 0.12065 -0.305054)
			(stroke
				(width 0.1)
				(type default)
			)
			(layer "B.Fab")
		)
		(fp_line
			(start 0.67945 0.3048)
			(end 0.67945 -0.305054)
			(stroke
				(width 0.1)
				(type default)
			)
			(layer "B.Fab")
		)
		(pad "1" smd circle
			(at 0.40005 0 180)
			(size 0 0)
			(layers "B.Cu" "B.Mask" "B.Paste")
			(net "P3V3_AUX")
		)
		(pad "2" smd circle
			(at -0.40005 0 180)
			(size 0 0)
			(layers "B.Cu" "B.Mask" "B.Paste")
			(net "GND")
		)
	)
	(footprint ""
		(layer "B.Cu")
		(at 185.166 -363.2581)
		(property "Reference" "PC7003"
			(at 0 0 0)
			(layer "B.SilkS")
			(hide yes)
			(effects
				(font
					(size 1.27 1.27)
				)
				(justify mirror)
			)
		)
		(property "Value" ""
			(at 0 0 0)
			(layer "B.Fab")
			(effects
				(font
					(size 1.27 1.27)
				)
				(justify mirror)
			)
		)
		(duplicate_pad_numbers_are_jumpers no)
		(fp_line
			(start -1.524 -0.762)
			(end -1.524 0.762)
			(stroke
				(width 0.1524)
				(type default)
			)
			(layer "B.SilkS")
		)
		(fp_line
			(start -1.524 0.762)
			(end 1.524 0.762)
			(stroke
				(width 0.1524)
				(type default)
			)
			(layer "B.SilkS")
		)
		(fp_line
			(start 1.524 -0.762)
			(end -1.524 -0.762)
			(stroke
				(width 0.1524)
				(type default)
			)
			(layer "B.SilkS")
		)
		(fp_line
			(start 1.524 0.762)
			(end 1.524 -0.762)
			(stroke
				(width 0.1524)
				(type default)
			)
			(layer "B.SilkS")
		)
		(fp_line
			(start -1.1049 -0.724916)
			(end 1.1049 -0.724916)
			(stroke
				(width 0.1)
				(type default)
			)
			(layer "B.Fab")
		)
		(fp_line
			(start -1.1049 0.724916)
			(end -1.1049 -0.724916)
			(stroke
				(width 0.1)
				(type default)
			)
			(layer "B.Fab")
		)
		(fp_line
			(start 1.1049 -0.724916)
			(end 1.1049 0.724916)
			(stroke
				(width 0.1)
				(type default)
			)
			(layer "B.Fab")
		)
		(fp_line
			(start 1.1049 0.724916)
			(end -1.1049 0.724916)
			(stroke
				(width 0.1)
				(type default)
			)
			(layer "B.Fab")
		)
		(pad "1" smd rect
			(at 0.889 0)
			(size 1.016 1.27)
			(layers "B.Cu" "B.Mask" "B.Paste")
			(net "SW_P12V_AUX_PVDD11_S3_P1_FLT")
		)
		(pad "2" smd rect
			(at -0.889 0)
			(size 1.016 1.27)
			(layers "B.Cu" "B.Mask" "B.Paste")
			(net "GND")
		)
	)
	(footprint ""
		(layer "B.Cu")
		(at 289.042856 -427.359572)
		(property "Reference" "C1708"
			(at 0 0 0)
			(layer "B.SilkS")
			(hide yes)
			(effects
				(font
					(size 1.27 1.27)
				)
				(justify mirror)
			)
		)
		(property "Value" ""
			(at 0 0 0)
			(layer "B.Fab")
			(effects
				(font
					(size 1.27 1.27)
				)
				(justify mirror)
			)
		)
		(duplicate_pad_numbers_are_jumpers no)
		(fp_line
			(start -0.7874 -0.4064)
			(end -0.7874 0.4064)
			(stroke
				(width 0.1524)
				(type default)
			)
			(layer "B.SilkS")
		)
		(fp_line
			(start -0.7874 0.4064)
			(end 0.7874 0.4064)
			(stroke
				(width 0.1524)
				(type default)
			)
			(layer "B.SilkS")
		)
		(fp_line
			(start 0.7874 -0.4064)
			(end -0.7874 -0.4064)
			(stroke
				(width 0.1524)
				(type default)
			)
			(layer "B.SilkS")
		)
		(fp_line
			(start 0.7874 0.4064)
			(end 0.7874 -0.4064)
			(stroke
				(width 0.1524)
				(type default)
			)
			(layer "B.SilkS")
		)
		(fp_line
			(start -0.67945 -0.3048)
			(end -0.67945 0.3048)
			(stroke
				(width 0.1)
				(type default)
			)
			(layer "B.Fab")
		)
		(fp_line
			(start -0.67945 0.3048)
			(end -0.120396 0.3048)
			(stroke
				(width 0.1)
				(type default)
			)
			(layer "B.Fab")
		)
		(fp_line
			(start -0.12065 -0.3048)
			(end -0.67945 -0.3048)
			(stroke
				(width 0.1)
				(type default)
			)
			(layer "B.Fab")
		)
		(fp_line
			(start -0.12065 -0.2794)
			(end -0.12065 -0.3048)
			(stroke
				(width 0.1)
				(type default)
			)
			(layer "B.Fab")
		)
		(fp_line
			(start -0.120396 0.2794)
			(end 0.12065 0.2794)
			(stroke
				(width 0.1)
				(type default)
			)
			(layer "B.Fab")
		)
		(fp_line
			(start -0.120396 0.3048)
			(end -0.120396 0.2794)
			(stroke
				(width 0.1)
				(type default)
			)
			(layer "B.Fab")
		)
		(fp_line
			(start 0.12065 -0.305054)
			(end 0.12065 -0.2794)
			(stroke
				(width 0.1)
				(type default)
			)
			(layer "B.Fab")
		)
		(fp_line
			(start 0.12065 -0.2794)
			(end -0.12065 -0.2794)
			(stroke
				(width 0.1)
				(type default)
			)
			(layer "B.Fab")
		)
		(fp_line
			(start 0.12065 0.2794)
			(end 0.12065 0.3048)
			(stroke
				(width 0.1)
				(type default)
			)
			(layer "B.Fab")
		)
		(fp_line
			(start 0.12065 0.3048)
			(end 0.67945 0.3048)
			(stroke
				(width 0.1)
				(type default)
			)
			(layer "B.Fab")
		)
		(fp_line
			(start 0.67945 -0.305054)
			(end 0.12065 -0.305054)
			(stroke
				(width 0.1)
				(type default)
			)
			(layer "B.Fab")
		)
		(fp_line
			(start 0.67945 0.3048)
			(end 0.67945 -0.305054)
			(stroke
				(width 0.1)
				(type default)
			)
			(layer "B.Fab")
		)
		(pad "1" smd circle
			(at 0.40005 0 180)
			(size 0 0)
			(layers "B.Cu" "B.Mask" "B.Paste")
			(net "P3V3_AUX")
		)
		(pad "2" smd circle
			(at -0.40005 0 180)
			(size 0 0)
			(layers "B.Cu" "B.Mask" "B.Paste")
			(net "GND")
		)
	)
)
